(kicad_pcb
	(version 20241229)
	(generator "pcbnew")
	(generator_version "9.0")
	(general
		(thickness 1.59)
		(legacy_teardrops no)
	)
	(paper "A3")
	(title_block
		(title "usb-c-power-adapter")
		(date "2025-06-24")
		(rev "1.1.2")
		(company "Antmicro")
		(comment 9 "footprints 68-72 of 122")
	)
	(layers
		(0 "F.Cu" signal)
		(4 "In1.Cu" signal)
		(6 "In2.Cu" signal)
		(2 "B.Cu" signal)
		(9 "F.Adhes" user "F.Adhesive")
		(11 "B.Adhes" user "B.Adhesive")
		(13 "F.Paste" user)
		(15 "B.Paste" user)
		(5 "F.SilkS" user "F.Silkscreen")
		(7 "B.SilkS" user "B.Silkscreen")
		(1 "F.Mask" user)
		(3 "B.Mask" user)
		(17 "Dwgs.User" user "User.Drawings")
		(19 "Cmts.User" user "User.Comments")
		(21 "Eco1.User" user "User.Eco1")
		(23 "Eco2.User" user "User.Eco2")
		(25 "Edge.Cuts" user)
		(27 "Margin" user)
		(31 "F.CrtYd" user "F.Courtyard")
		(29 "B.CrtYd" user "B.Courtyard")
		(35 "F.Fab" user)
		(33 "B.Fab" user)
	)
	(footprint "antmicro-footprints:C_0402_1005Metric"
		(layer "F.Cu")
		(at 100 85.577)
		(descr "Capacitor SMD 0402")
		(tags "capacitor SMD 0402")
		(property "Reference" "C15"
			(at 1.092 0.529 0)
			(layer "F.SilkS")
			(effects
				(font
					(size 0.7 0.7)
					(thickness 0.15)
				)
				(justify left bottom)
			)
		)
		(property "Value" "C_100n_50V_X8L_0402"
			(at -1.022927 2.155213 0)
			(layer "F.Fab")
			(effects
				(font
					(size 0.7 0.7)
					(thickness 0.15)
				)
				(justify left bottom)
			)
		)
		(property "Datasheet" "https://www.murata.com/products/productdetail?partno=GCM155L8EH104KE07%23"
			(at 0 0 0)
			(layer "F.Fab")
			(hide yes)
			(effects
				(font
					(size 1.27 1.27)
					(thickness 0.15)
				)
			)
		)
		(property "Description" "SMD Multilayer Ceramic Capacitor, 100nF, 50V, 0402, ±10%, X8L"
			(at 0 0 0)
			(layer "F.Fab")
			(hide yes)
			(effects
				(font
					(size 1.27 1.27)
					(thickness 0.15)
				)
			)
		)
		(property "MPN" "GCM155L8EH104KE07D"
			(at 0 0 0)
			(unlocked yes)
			(layer "F.Fab")
			(hide yes)
			(effects
				(font
					(size 1 1)
					(thickness 0.15)
				)
			)
		)
		(property "Val" "100n"
			(at 0 0 0)
			(unlocked yes)
			(layer "F.Fab")
			(hide yes)
			(effects
				(font
					(size 1 1)
					(thickness 0.15)
				)
			)
		)
		(property "Voltage" "50V"
			(at 0 0 0)
			(unlocked yes)
			(layer "F.Fab")
			(hide yes)
			(effects
				(font
					(size 1 1)
					(thickness 0.15)
				)
			)
		)
		(property "Dielectric" "X8L"
			(at 0 0 0)
			(unlocked yes)
			(layer "F.Fab")
			(hide yes)
			(effects
				(font
					(size 1 1)
					(thickness 0.15)
				)
			)
		)
		(property "Manufacturer" "Murata"
			(at 0 0 0)
			(unlocked yes)
			(layer "F.Fab")
			(hide yes)
			(effects
				(font
					(size 1 1)
					(thickness 0.15)
				)
			)
		)
		(property "License" "Apache-2.0"
			(at 0 0 0)
			(unlocked yes)
			(layer "F.Fab")
			(hide yes)
			(effects
				(font
					(size 1 1)
					(thickness 0.15)
				)
			)
		)
		(property "Author" "Antmicro"
			(at 0 0 0)
			(unlocked yes)
			(layer "F.Fab")
			(hide yes)
			(effects
				(font
					(size 1 1)
					(thickness 0.15)
				)
			)
		)
		(sheetname "/DC-DC Converters/")
		(sheetfile "dc-dc_converters.kicad_sch")
		(attr smd)
		(fp_rect
			(start -0.925 -0.47)
			(end 0.925 0.47)
			(stroke
				(width 0.05)
				(type default)
			)
			(fill no)
			(layer "F.CrtYd")
		)
		(fp_line
			(start -0.494 -0.25)
			(end 0.504 -0.25)
			(stroke
				(width 0.15)
				(type solid)
			)
			(layer "F.Fab")
		)
		(fp_line
			(start -0.494 0.248)
			(end -0.494 -0.25)
			(stroke
				(width 0.15)
				(type solid)
			)
			(layer "F.Fab")
		)
		(fp_line
			(start 0.504 -0.25)
			(end 0.504 0.248)
			(stroke
				(width 0.15)
				(type solid)
			)
			(layer "F.Fab")
		)
		(fp_line
			(start 0.504 0.248)
			(end -0.494 0.248)
			(stroke
				(width 0.15)
				(type solid)
			)
			(layer "F.Fab")
		)
		(pad "1" smd roundrect
			(at -0.48 0)
			(size 0.59 0.64)
			(layers "F.Cu" "F.Mask" "F.Paste")
			(roundrect_rratio 0.25)
			(net 2 "GND")
			(pintype "passive")
		)
		(pad "2" smd roundrect
			(at 0.48 0)
			(size 0.59 0.64)
			(layers "F.Cu" "F.Mask" "F.Paste")
			(roundrect_rratio 0.25)
			(net 5 "+12V")
			(pintype "passive")
		)
	)
	(footprint "antmicro-footprints:Conn_Molex_Nano-Fit_1x2_1053131102"
		(layer "F.Cu")
		(at 86.93 101.9275)
		(property "Reference" "J4"
			(at 2.07 0.5725 90)
			(layer "F.SilkS")
			(effects
				(font
					(size 0.7 0.7)
					(thickness 0.15)
				)
				(justify left bottom)
			)
		)
		(property "Value" "Molex_Nano-Fit_1x2_1053131202"
			(at 0 13.1 0)
			(layer "F.Fab")
			(effects
				(font
					(size 0.7 0.7)
					(thickness 0.15)
				)
				(justify left bottom)
			)
		)
		(property "Datasheet" "https://tools.molex.com/pdm_docs/ps/PS-105300-100-001.pdf"
			(at 0 0 0)
			(layer "F.Fab")
			(hide yes)
			(effects
				(font
					(size 1.27 1.27)
					(thickness 0.15)
				)
			)
		)
		(property "Description" "Rectangular connector, header, Through Hole, Right Angle 2 position"
			(at 0 0 0)
			(layer "F.Fab")
			(hide yes)
			(effects
				(font
					(size 1.27 1.27)
					(thickness 0.15)
				)
			)
		)
		(property "Manufacturer" "Molex"
			(at 0 0 0)
			(unlocked yes)
			(layer "F.Fab")
			(hide yes)
			(effects
				(font
					(size 1 1)
					(thickness 0.15)
				)
			)
		)
		(property "MPN" "1053131202"
			(at 0 0 0)
			(unlocked yes)
			(layer "F.Fab")
			(hide yes)
			(effects
				(font
					(size 1 1)
					(thickness 0.15)
				)
			)
		)
		(property "Author" "Antmicro"
			(at 0 0 0)
			(unlocked yes)
			(layer "F.Fab")
			(hide yes)
			(effects
				(font
					(size 1 1)
					(thickness 0.15)
				)
			)
		)
		(property "License" "Apache-2.0"
			(at 0 0 0)
			(unlocked yes)
			(layer "F.Fab")
			(hide yes)
			(effects
				(font
					(size 1 1)
					(thickness 0.15)
				)
			)
		)
		(sheetname "/DC-DC Converters/")
		(sheetfile "dc-dc_converters.kicad_sch")
		(attr through_hole)
		(fp_line
			(start -4.221 1.918)
			(end -4.221 10.38)
			(stroke
				(width 0.15)
				(type solid)
			)
			(layer "F.SilkS")
		)
		(fp_line
			(start -4.221 1.918)
			(end 1.719 1.918)
			(stroke
				(width 0.15)
				(type solid)
			)
			(layer "F.SilkS")
		)
		(fp_line
			(start -4.221 10.38)
			(end 1.719 10.38)
			(stroke
				(width 0.15)
				(type solid)
			)
			(layer "F.SilkS")
		)
		(fp_line
			(start 0.998 1.199)
			(end 1.699 1.199)
			(stroke
				(width 0.15)
				(type solid)
			)
			(layer "F.SilkS")
		)
		(fp_line
			(start 1.35 1.55)
			(end 1.35 0.848)
			(stroke
				(width 0.15)
				(type solid)
			)
			(layer "F.SilkS")
		)
		(fp_line
			(start 1.719 1.918)
			(end 1.719 10.38)
			(stroke
				(width 0.15)
				(type solid)
			)
			(layer "F.SilkS")
		)
		(fp_rect
			(start -4.721 -1.1)
			(end 2.219 12.1)
			(stroke
				(width 0.05)
				(type solid)
			)
			(fill no)
			(layer "F.CrtYd")
		)
		(fp_text user "License: Apache-2.0"
			(at -4.221 16.949 0)
			(layer "F.Fab")
			(effects
				(font
					(size 0.7 0.7)
					(thickness 0.15)
				)
				(justify left bottom)
			)
		)
		(fp_text user "Author: Antmicro"
			(at -4.221 15.749 0)
			(layer "F.Fab")
			(effects
				(font
					(size 0.7 0.7)
					(thickness 0.15)
				)
				(justify left bottom)
			)
		)
		(fp_text user "${REFERENCE}"
			(at -4.221 14.55 0)
			(layer "F.Fab")
			(effects
				(font
					(size 0.7 0.7)
					(thickness 0.15)
				)
				(justify left bottom)
			)
		)
		(pad "" np_thru_hole circle
			(at -2.5 7.179)
			(size 1.71 1.71)
			(drill 1.7)
			(layers "*.Cu" "*.Mask")
		)
		(pad "" np_thru_hole circle
			(at 0 7.179)
			(size 1.71 1.71)
			(drill 1.7)
			(layers "*.Cu" "*.Mask")
		)
		(pad "1" thru_hole circle
			(at 0 0)
			(size 2 2)
			(drill 1.3)
			(layers "*.Cu" "*.Mask")
			(remove_unused_layers no)
			(net 26 "Net-(D5-C)")
			(pintype "input")
		)
		(pad "2" thru_hole circle
			(at -2.5 0)
			(size 2 2)
			(drill 1.3)
			(layers "*.Cu" "*.Mask")
			(remove_unused_layers no)
			(net 2 "GND")
			(pintype "input")
		)
	)
	(footprint "antmicro-footprints:C_0402_1005Metric"
		(layer "F.Cu")
		(at 84.176 78.525 180)
		(descr "Capacitor SMD 0402")
		(tags "capacitor SMD 0402")
		(property "Reference" "C19"
			(at 1.239 -2.141 180)
			(layer "F.SilkS")
			(effects
				(font
					(size 0.7 0.7)
					(thickness 0.15)
				)
				(justify left bottom)
			)
		)
		(property "Value" "C_100n_50V_X8L_0402"
			(at -1.022927 2.155213 0)
			(layer "F.Fab")
			(effects
				(font
					(size 0.7 0.7)
					(thickness 0.15)
				)
				(justify right bottom)
			)
		)
		(property "Datasheet" "https://www.murata.com/products/productdetail?partno=GCM155L8EH104KE07%23"
			(at 0 0 180)
			(layer "F.Fab")
			(hide yes)
			(effects
				(font
					(size 1.27 1.27)
					(thickness 0.15)
				)
			)
		)
		(property "Description" "SMD Multilayer Ceramic Capacitor, 100nF, 50V, 0402, ±10%, X8L"
			(at 0 0 180)
			(layer "F.Fab")
			(hide yes)
			(effects
				(font
					(size 1.27 1.27)
					(thickness 0.15)
				)
			)
		)
		(property "MPN" "GCM155L8EH104KE07D"
			(at 0 0 180)
			(unlocked yes)
			(layer "F.Fab")
			(hide yes)
			(effects
				(font
					(size 1 1)
					(thickness 0.15)
				)
			)
		)
		(property "Val" "100n"
			(at 0 0 180)
			(unlocked yes)
			(layer "F.Fab")
			(hide yes)
			(effects
				(font
					(size 1 1)
					(thickness 0.15)
				)
			)
		)
		(property "Voltage" "50V"
			(at 0 0 180)
			(unlocked yes)
			(layer "F.Fab")
			(hide yes)
			(effects
				(font
					(size 1 1)
					(thickness 0.15)
				)
			)
		)
		(property "Dielectric" "X8L"
			(at 0 0 180)
			(unlocked yes)
			(layer "F.Fab")
			(hide yes)
			(effects
				(font
					(size 1 1)
					(thickness 0.15)
				)
			)
		)
		(property "Manufacturer" "Murata"
			(at 0 0 180)
			(unlocked yes)
			(layer "F.Fab")
			(hide yes)
			(effects
				(font
					(size 1 1)
					(thickness 0.15)
				)
			)
		)
		(property "License" "Apache-2.0"
			(at 0 0 180)
			(unlocked yes)
			(layer "F.Fab")
			(hide yes)
			(effects
				(font
					(size 1 1)
					(thickness 0.15)
				)
			)
		)
		(property "Author" "Antmicro"
			(at 0 0 180)
			(unlocked yes)
			(layer "F.Fab")
			(hide yes)
			(effects
				(font
					(size 1 1)
					(thickness 0.15)
				)
			)
		)
		(sheetname "/USB PD/")
		(sheetfile "usb_pd.kicad_sch")
		(attr smd)
		(fp_rect
			(start -0.925 -0.47)
			(end 0.925 0.47)
			(stroke
				(width 0.05)
				(type default)
			)
			(fill no)
			(layer "F.CrtYd")
		)
		(fp_line
			(start 0.504 0.248)
			(end -0.494 0.248)
			(stroke
				(width 0.15)
				(type solid)
			)
			(layer "F.Fab")
		)
		(fp_line
			(start 0.504 -0.25)
			(end 0.504 0.248)
			(stroke
				(width 0.15)
				(type solid)
			)
			(layer "F.Fab")
		)
		(fp_line
			(start -0.494 0.248)
			(end -0.494 -0.25)
			(stroke
				(width 0.15)
				(type solid)
			)
			(layer "F.Fab")
		)
		(fp_line
			(start -0.494 -0.25)
			(end 0.504 -0.25)
			(stroke
				(width 0.15)
				(type solid)
			)
			(layer "F.Fab")
		)
		(pad "1" smd roundrect
			(at -0.48 0 180)
			(size 0.59 0.64)
			(layers "F.Cu" "F.Mask" "F.Paste")
			(roundrect_rratio 0.25)
			(net 20 "Net-(C19-Pad1)")
			(pintype "passive")
		)
		(pad "2" smd roundrect
			(at 0.48 0 180)
			(size 0.59 0.64)
			(layers "F.Cu" "F.Mask" "F.Paste")
			(roundrect_rratio 0.25)
			(net 3 "VCC")
			(pintype "passive")
		)
	)
	(footprint "antmicro-footprints:C_0805_2012Metric"
		(layer "F.Cu")
		(at 89.2 84.7 90)
		(descr "Capacitor SMD 0805")
		(tags "capacitor SMD 0805")
		(property "Reference" "C4"
			(at -3.04 -5.004 90)
			(layer "F.SilkS")
			(effects
				(font
					(size 0.7 0.7)
					(thickness 0.15)
				)
				(justify left bottom)
			)
		)
		(property "Value" "C_10u_0805_35V"
			(at -2.055717 1.963152 90)
			(layer "F.Fab")
			(effects
				(font
					(size 0.7 0.7)
					(thickness 0.15)
				)
				(justify left bottom)
			)
		)
		(property "Datasheet" "https://www.murata.com/products/productdetail?partno=GRM21BR6YA106KE43%23"
			(at 0 0 90)
			(layer "F.Fab")
			(hide yes)
			(effects
				(font
					(size 1.27 1.27)
					(thickness 0.15)
				)
			)
		)
		(property "Description" "SMD Multilayer Ceramic Capacitor, 10 µF, 35 V, 0805 [2012 Metric], ± 10%, X5R, GRM Series"
			(at 0 0 90)
			(layer "F.Fab")
			(hide yes)
			(effects
				(font
					(size 1.27 1.27)
					(thickness 0.15)
				)
			)
		)
		(property "MPN" "GRM21BR6YA106KE43L"
			(at 0 0 90)
			(unlocked yes)
			(layer "F.Fab")
			(hide yes)
			(effects
				(font
					(size 1 1)
					(thickness 0.15)
				)
			)
		)
		(property "Manufacturer" "Murata"
			(at 0 0 90)
			(unlocked yes)
			(layer "F.Fab")
			(hide yes)
			(effects
				(font
					(size 1 1)
					(thickness 0.15)
				)
			)
		)
		(property "License" "Apache-2.0"
			(at 0 0 90)
			(unlocked yes)
			(layer "F.Fab")
			(hide yes)
			(effects
				(font
					(size 1 1)
					(thickness 0.15)
				)
			)
		)
		(property "Author" "Antmicro"
			(at 0 0 90)
			(unlocked yes)
			(layer "F.Fab")
			(hide yes)
			(effects
				(font
					(size 1 1)
					(thickness 0.15)
				)
			)
		)
		(property "Val" "10u"
			(at 0 0 90)
			(unlocked yes)
			(layer "F.Fab")
			(hide yes)
			(effects
				(font
					(size 1 1)
					(thickness 0.15)
				)
			)
		)
		(property "Voltage" "35V"
			(at 0 0 90)
			(unlocked yes)
			(layer "F.Fab")
			(hide yes)
			(effects
				(font
					(size 1 1)
					(thickness 0.15)
				)
			)
		)
		(property "Dielectric" ""
			(at 0 0 90)
			(unlocked yes)
			(layer "F.Fab")
			(hide yes)
			(effects
				(font
					(size 1 1)
					(thickness 0.15)
				)
			)
		)
		(property "Public" "False"
			(at 0 0 90)
			(unlocked yes)
			(layer "F.Fab")
			(hide yes)
			(effects
				(font
					(size 1 1)
					(thickness 0.15)
				)
			)
		)
		(sheetname "/DC-DC Converters/")
		(sheetfile "dc-dc_converters.kicad_sch")
		(attr smd)
		(fp_line
			(start -0.3 -0.7)
			(end 0.3 -0.7)
			(stroke
				(width 0.15)
				(type solid)
			)
			(layer "F.SilkS")
		)
		(fp_line
			(start -0.3 0.7)
			(end 0.3 0.7)
			(stroke
				(width 0.15)
				(type solid)
			)
			(layer "F.SilkS")
		)
		(fp_rect
			(start 1.95 -0.9)
			(end -1.95 0.9)
			(stroke
				(width 0.05)
				(type default)
			)
			(fill no)
			(layer "F.CrtYd")
		)
		(fp_rect
			(start -0.95 -0.675)
			(end 0.95 0.675)
			(stroke
				(width 0.15)
				(type solid)
			)
			(fill no)
			(layer "F.Fab")
		)
		(pad "1" smd roundrect
			(at -1.1 0 90)
			(size 1.2 1.3)
			(layers "F.Cu" "F.Mask" "F.Paste")
			(roundrect_rratio 0.25)
			(net 2 "GND")
			(pintype "passive")
		)
		(pad "2" smd roundrect
			(at 1.1 0 90)
			(size 1.2 1.3)
			(layers "F.Cu" "F.Mask" "F.Paste")
			(roundrect_rratio 0.25)
			(net 12 "Net-(U2-V_{CIN})")
			(pintype "passive")
		)
	)
	(footprint "antmicro-footprints:R_0402_1005Metric"
		(layer "F.Cu")
		(at 91.776 73.55 180)
		(descr "Resistor SMD 0402")
		(tags "resistor SMD 0402")
		(property "Reference" "R19"
			(at 1.126 -1.4 180)
			(layer "F.SilkS")
			(effects
				(font
					(size 0.7 0.7)
					(thickness 0.15)
				)
				(justify left bottom)
			)
		)
		(property "Value" "R_470R_0402"
			(at -1.011843 1.772047 180)
			(layer "F.Fab")
			(effects
				(font
					(size 0.7 0.7)
					(thickness 0.15)
				)
				(justify left bottom)
			)
		)
		(property "Datasheet" "https://www.bourns.com/docs/product-datasheets/cr.pdf"
			(at 0 0 180)
			(layer "F.Fab")
			(hide yes)
			(effects
				(font
					(size 1.27 1.27)
					(thickness 0.15)
				)
			)
		)
		(property "Description" "SMD Chip Resistor, 470 ohm, ± 1%, 62.5 mW, 0402 [1005 Metric], Thick Film, General Purpose"
			(at 0 0 180)
			(layer "F.Fab")
			(hide yes)
			(effects
				(font
					(size 1.27 1.27)
					(thickness 0.15)
				)
			)
		)
		(property "MPN" "CR0402-FX-4700GLF"
			(at 0 0 180)
			(unlocked yes)
			(layer "F.Fab")
			(hide yes)
			(effects
				(font
					(size 1 1)
					(thickness 0.15)
				)
			)
		)
		(property "Manufacturer" "Bourns"
			(at 0 0 180)
			(unlocked yes)
			(layer "F.Fab")
			(hide yes)
			(effects
				(font
					(size 1 1)
					(thickness 0.15)
				)
			)
		)
		(property "License" "Apache-2.0"
			(at 0 0 180)
			(unlocked yes)
			(layer "F.Fab")
			(hide yes)
			(effects
				(font
					(size 1 1)
					(thickness 0.15)
				)
			)
		)
		(property "Author" "Antmicro"
			(at 0 0 180)
			(unlocked yes)
			(layer "F.Fab")
			(hide yes)
			(effects
				(font
					(size 1 1)
					(thickness 0.15)
				)
			)
		)
		(property "Val" "470R"
			(at 0 0 180)
			(unlocked yes)
			(layer "F.Fab")
			(hide yes)
			(effects
				(font
					(size 1 1)
					(thickness 0.15)
				)
			)
		)
		(property "Tolerance" "1%"
			(at 0 0 180)
			(unlocked yes)
			(layer "F.Fab")
			(hide yes)
			(effects
				(font
					(size 1 1)
					(thickness 0.15)
				)
			)
		)
		(sheetname "/USB PD/")
		(sheetfile "usb_pd.kicad_sch")
		(attr smd)
		(fp_rect
			(start -0.925 -0.47)
			(end 0.925 0.47)
			(stroke
				(width 0.05)
				(type default)
			)
			(fill no)
			(layer "F.CrtYd")
		)
		(fp_rect
			(start -0.5 -0.25)
			(end 0.5 0.25)
			(stroke
				(width 0.15)
				(type solid)
			)
			(fill no)
			(layer "F.Fab")
		)
		(pad "1" smd roundrect
			(at -0.48 0 180)
			(size 0.59 0.64)
			(layers "F.Cu" "F.Mask" "F.Paste")
			(roundrect_rratio 0.25)
			(net 63 "Net-(D1-C)")
			(pintype "passive")
		)
		(pad "2" smd roundrect
			(at 0.48 0 180)
			(size 0.59 0.64)
			(layers "F.Cu" "F.Mask" "F.Paste")
			(roundrect_rratio 0.25)
			(net 6 "VBUS")
			(pintype "passive")
		)
	)
)
